# BASEBOARD_FAB2 (Tioga Pass) — schematic netlist excerpt (pin names and nets, part order shuffled) for the footprints in the layout excerpt that follows; sources: Cadence DE-HDL packaged netlist, KiCad conversion of Wiwynn_Tioga_Pass_MB.brd

J4G2  SCONN288_H44441004  SCONN  pkg PIP  page 45
  \12v\(1)  = P12V_NVDIMM_ABC
  VSS(93)  = GND
  DQ(4)  = M_B_DQ<5>
  VSS(92)  = GND
  DQ(0)  = M_B_DQ<1>
  VSS(91)  = GND
  DQS9P  = M_B_DQS_DP<9>
  DQS9N  = M_B_DQS_DN<9>
  VSS(90)  = GND
  DQ(6)  = M_B_DQ<7>
  VSS(89)  = GND
  DQ(2)  = M_B_DQ<3>
  VSS(88)  = GND
  DQ(12)  = M_B_DQ<13>
  VSS(87)  = GND
  DQ(8)  = M_B_DQ<9>
  VSS(86)  = GND
  DQS10P  = M_B_DQS_DP<10>
  DQS10N  = M_B_DQS_DN<10>
  VSS(85)  = GND
  DQ(14)  = M_B_DQ<15>
  VSS(84)  = GND
  DQ(10)  = M_B_DQ<11>
  VSS(83)  = GND
  DQ(20)  = M_B_DQ<21>
  VSS(82)  = GND
  DQ(16)  = M_B_DQ<17>
  VSS(81)  = GND
  DQS11P  = M_B_DQS_DP<11>
  DQS11N  = M_B_DQS_DN<11>
  VSS(80)  = GND
  DQ(22)  = M_B_DQ<23>
  VSS(79)  = GND
  DQ(18)  = M_B_DQ<19>
  VSS(78)  = GND
  DQ(28)  = M_B_DQ<29>
  VSS(77)  = GND
  DQ(24)  = M_B_DQ<25>
  VSS(76)  = GND
  DQS12P  = M_B_DQS_DP<12>
  DQS12N  = M_B_DQS_DN<12>
  VSS(75)  = GND
  DQ(30)  = M_B_DQ<31>
  VSS(74)  = GND
  DQ(26)  = M_B_DQ<27>
  VSS(73)  = GND
  CB(4)  = M_B_ECC<5>
  VSS(72)  = GND
  CB(0)  = M_B_ECC<1>
  VSS(71)  = GND
  DQS17P  = M_B_DQS_DP<17>
  DQS17N  = M_B_DQS_DN<17>
  VSS(70)  = GND
  CB(6)  = M_B_ECC<7>
  VSS(69)  = GND
  CB(2)  = M_B_ECC<3>
  VSS(68)  = GND
  RESET_N  = M_ABC_RST_N
  VDD(25)  = PVDDQ_ABC
  CKE(0)  = M_B_CKE<0>
  VDD(24)  = PVDDQ_ABC
  ACT_N  = M_B_ACT_N
  BG(0)  = M_B_BG<0>
  VDD(23)  = PVDDQ_ABC
  A12  = M_B_MA<12>
  A9  = M_B_MA<9>
  VDD(22)  = PVDDQ_ABC
  A8  = M_B_MA<8>
  A6  = M_B_MA<6>
  VDD(21)  = PVDDQ_ABC
  A3  = M_B_MA<3>
  A1  = M_B_MA<1>
  VDD(20)  = PVDDQ_ABC
  CK0P  = M_B_CLK_DP<0>
  CK0N  = M_B_CLK_DN<0>
  VDD(19)  = PVDDQ_ABC
  VTT(1)  = PVTT_ABC
  EVENT_N  = FM_DIMM_EVENT_COD_N
  A0  = M_B_MA<0>
  VDD(18)  = PVDDQ_ABC
  BA(0)  = M_B_BA<0>
  A16_RAS_N  = M_B_MA<16>
  VDD(17)  = PVDDQ_ABC
  S0_N  = M_B_CS_N<0>
  VDD(16)  = PVDDQ_ABC
  A15_CAS_N  = M_B_MA<15>
  ODT(0)  = M_B_ODT<0>
  VDD(15)  = PVDDQ_ABC
  S1_N  = M_B_CS_N<1>
  VDD(14)  = PVDDQ_ABC
  ODT(1)  = M_B_ODT<1>
  VDD(13)  = PVDDQ_ABC
  S2_N_C(0)  = M_B_CS_N<2>
  VSS(67)  = GND
  DQ(36)  = M_B_DQ<37>
  VSS(66)  = GND
  DQ(32)  = M_B_DQ<33>
  VSS(65)  = GND
  DQS13P  = M_B_DQS_DP<13>
  DQS13N  = M_B_DQS_DN<13>
  VSS(64)  = GND
  DQ(38)  = M_B_DQ<39>
  VSS(63)  = GND
  DQ(34)  = M_B_DQ<35>
  VSS(62)  = GND
  DQ(44)  = M_B_DQ<45>
  VSS(61)  = GND
  DQ(40)  = M_B_DQ<41>
  VSS(60)  = GND
  DQS14P  = M_B_DQS_DP<14>
  DQS14N  = M_B_DQS_DN<14>
  VSS(59)  = GND
  DQ(46)  = M_B_DQ<47>
  VSS(58)  = GND
  DQ(42)  = M_B_DQ<43>
  VSS(57)  = GND
  DQ(52)  = M_B_DQ<53>
  VSS(56)  = GND
  DQ(48)  = M_B_DQ<49>
  VSS(55)  = GND
  DQS15P  = M_B_DQS_DP<15>
  DQS15N  = M_B_DQS_DN<15>
  VSS(54)  = GND
  DQ(54)  = M_B_DQ<55>
  VSS(53)  = GND
  DQ(50)  = M_B_DQ<51>
  VSS(52)  = GND
  DQ(60)  = M_B_DQ<61>
  VSS(51)  = GND
  DQ(56)  = M_B_DQ<57>
  VSS(50)  = GND
  DQS16P  = M_B_DQS_DP<16>
  DQS16N  = M_B_DQS_DN<16>
  VSS(49)  = GND
  DQ(62)  = M_B_DQ<63>
  VSS(48)  = GND
  DQ(58)  = M_B_DQ<59>
  VSS(47)  = GND
  SA(0)  = GND
  SA(1)  = PVPP_ABC
  SCL  = SMB_DDR_ABC_VPP_SCL
  VPP(4)  = PVPP_ABC
  VPP(3)  = PVPP_ABC
  RFU(2)  = TP_CH_B_DIMM_B0_RFU_2
  \12v\(0)  = P12V_NVDIMM_ABC
  VREFCA  = M_B_VREF
  VSS(46)  = GND
  DQ(5)  = M_B_DQ<4>
  VSS(45)  = GND
  DQ(1)  = M_B_DQ<0>
  VSS(44)  = GND
  DQS0N  = M_B_DQS_DN<0>
  DQS0P  = M_B_DQS_DP<0>
  VSS(43)  = GND
  DQ(7)  = M_B_DQ<6>
  VSS(42)  = GND
  DQ(3)  = M_B_DQ<2>
  VSS(41)  = GND
  DQ(13)  = M_B_DQ<12>
  VSS(40)  = GND
  DQ(9)  = M_B_DQ<8>
  VSS(39)  = GND
  DQS1N  = M_B_DQS_DN<1>
  DQS1P  = M_B_DQS_DP<1>
  VSS(38)  = GND
  DQ(15)  = M_B_DQ<14>
  VSS(37)  = GND
  DQ(11)  = M_B_DQ<10>
  VSS(36)  = GND
  DQ(21)  = M_B_DQ<20>
  VSS(35)  = GND
  DQ(17)  = M_B_DQ<16>
  VSS(34)  = GND
  DQS2N  = M_B_DQS_DN<2>
  DQS2P  = M_B_DQS_DP<2>
  VSS(33)  = GND
  DQ(23)  = M_B_DQ<22>
  VSS(32)  = GND
  DQ(19)  = M_B_DQ<18>
  VSS(31)  = GND
  DQ(29)  = M_B_DQ<28>
  VSS(30)  = GND
  DQ(25)  = M_B_DQ<24>
  VSS(29)  = GND
  DQS3N  = M_B_DQS_DN<3>
  DQS3P  = M_B_DQS_DP<3>
  VSS(28)  = GND
  DQ(31)  = M_B_DQ<30>
  VSS(27)  = GND
  DQ(27)  = M_B_DQ<26>
  VSS(26)  = GND
  CB(5)  = M_B_ECC<4>
  VSS(25)  = GND
  CB(1)  = M_B_ECC<0>
  VSS(24)  = GND
  DQS8N  = M_B_DQS_DN<8>
  DQS8P  = M_B_DQS_DP<8>
  VSS(23)  = GND
  CB(7)  = M_B_ECC<6>
  VSS(22)  = GND
  CB(3)  = M_B_ECC<2>
  VSS(21)  = GND
  CKE(1)  = M_B_CKE<1>
  VDD(12)  = PVDDQ_ABC
  RFU(0)  = TP_CH_B_DIMM_B0_RFU_0
  VDD(11)  = PVDDQ_ABC
  BG(1)  = M_B_BG<1>
  ALERT_N  = M_B_ALERT_N
  VDD(10)  = PVDDQ_ABC
  A11  = M_B_MA<11>
  A7  = M_B_MA<7>
  VDD(9)  = PVDDQ_ABC
  A5  = M_B_MA<5>
  A4  = M_B_MA<4>
  VDD(8)  = PVDDQ_ABC
  A2  = M_B_MA<2>
  VDD(7)  = PVDDQ_ABC
  CK1P  = M_B_CLK_DP<1>
  CK1N  = M_B_CLK_DN<1>
  VDD(6)  = PVDDQ_ABC
  VTT(0)  = PVTT_ABC
  PAR  = M_B_PAR
  VDD(5)  = PVDDQ_ABC
  BA(1)  = M_B_BA<1>
  A10  = M_B_MA<10>
  VDD(4)  = PVDDQ_ABC
  RFU(1)  = TP_CH_B_DIMM_B0_RFU_1
  A14_WE_N  = M_B_MA<14>
  VDD(3)  = PVDDQ_ABC
  SAVE_N_NC  = FM_ADR_COMPLETE_ABC_N
  VDD(2)  = PVDDQ_ABC
  A13  = M_B_MA<13>
  VDD(1)  = PVDDQ_ABC
  A17  = M_B_MA<17>
  C(2)  = M_B_C<2>
  VDD(0)  = PVDDQ_ABC
  S3_N_C(1)  = M_B_CS_N<3>
  SA(2)  = GND
  VSS(20)  = GND
  DQ(37)  = M_B_DQ<36>
  VSS(19)  = GND
  DQ(33)  = M_B_DQ<32>
  VSS(18)  = GND
  DQS4N  = M_B_DQS_DN<4>
  DQS4P  = M_B_DQS_DP<4>
  VSS(17)  = GND
  DQ(39)  = M_B_DQ<38>
  VSS(16)  = GND
  DQ(35)  = M_B_DQ<34>
  VSS(15)  = GND
  DQ(45)  = M_B_DQ<44>
  VSS(14)  = GND
  DQ(41)  = M_B_DQ<40>
  VSS(13)  = GND
  DQS5N  = M_B_DQS_DN<5>
  DQS5P  = M_B_DQS_DP<5>
  VSS(12)  = GND
  DQ(47)  = M_B_DQ<46>
  VSS(11)  = GND
  DQ(43)  = M_B_DQ<42>
  VSS(10)  = GND
  DQ(53)  = M_B_DQ<52>
  VSS(9)  = GND
  DQ(49)  = M_B_DQ<48>
  VSS(8)  = GND
  DQS6N  = M_B_DQS_DN<6>
  DQS6P  = M_B_DQS_DP<6>
  VSS(7)  = GND
  DQ(55)  = M_B_DQ<54>
  VSS(6)  = GND
  DQ(51)  = M_B_DQ<50>
  VSS(5)  = GND
  DQ(61)  = M_B_DQ<60>
  VSS(4)  = GND
  DQ(57)  = M_B_DQ<56>
  VSS(3)  = GND
  DQS7N  = M_B_DQS_DN<7>
  DQS7P  = M_B_DQS_DP<7>
  VSS(2)  = GND
  DQ(63)  = M_B_DQ<62>
  VSS(1)  = GND
  DQ(59)  = M_B_DQ<58>
  VSS(0)  = GND
  VDDSPD  = PVPP_ABC
  SDA  = SMB_DDR_ABC_VPP_SDA
  VPP(1)  = PVPP_ABC
  VPP(0)  = PVPP_ABC
  VPP(2)  = PVPP_ABC

(kicad_pcb
	(version 20260206)
	(generator "pcbnew")
	(generator_version "10.0")
	(general
		(thickness 1.6)
		(legacy_teardrops no)
	)
	(paper "A4")
	(title_block
		(title "Wiwynn_Tioga_Pass_MB.brd")
		(comment 1 "Tioga Pass / footprint 1899 of 4770 (J4G2), pads 1-51 of 291")
	)
	(layers
		(0 "F.Cu" signal "TOP")
		(4 "In1.Cu" signal "L2GND")
		(6 "In2.Cu" signal "L3")
		(8 "In3.Cu" signal "L4GND")
		(10 "In4.Cu" signal "L5")
		(12 "In5.Cu" signal "L6GND")
		(14 "In6.Cu" signal "L7VCC")
		(16 "In7.Cu" signal "L8VCC")
		(18 "In8.Cu" signal "L9GND")
		(20 "In9.Cu" signal "L10")
		(22 "In10.Cu" signal "L11GND")
		(24 "In11.Cu" signal "L12")
		(26 "In12.Cu" signal "L13GND")
		(2 "B.Cu" signal "BOTTOM")
		(9 "F.Adhes" user "F.Adhesive")
		(11 "B.Adhes" user "B.Adhesive")
		(13 "F.Paste" user "Package Geometry/Pastemask Top")
		(15 "B.Paste" user "Package Geometry/Pastemask Bottom")
		(5 "F.SilkS" user "Ref Des/Silkscreen Top")
		(7 "B.SilkS" user "Ref Des/Silkscreen Bottom")
		(1 "F.Mask" user "Board Geometry/Soldermask Top")
		(3 "B.Mask" user "Board Geometry/Soldermask Bottom")
		(17 "Dwgs.User" user "User.Drawings")
		(19 "Cmts.User" user "User.Comments")
		(21 "Eco1.User" user "User.Eco1")
		(23 "Eco2.User" user "User.Eco2")
		(25 "Edge.Cuts" user "Board Geometry/Outline")
		(27 "Margin" user)
		(31 "F.CrtYd" user "Package Geometry/Place Bound Top")
		(29 "B.CrtYd" user "Package Geometry/Place Bound Bottom")
		(35 "F.Fab" user "Ref Des/Assembly Top")
		(33 "B.Fab" user "Ref Des/Assembly Bottom")
	)
	(footprint ""
		(layer "F.Cu")
		(at 194.700398 -5.822442 90)
		(property "Reference" "J4G2"
			(at 6.596888 37.58311 0)
			(unlocked yes)
			(layer "F.SilkS")
			(effects
				(font
					(size 0.7874 0.5842)
					(thickness 0.1524)
				)
				(justify left)
			)
		)
		(property "Value" ""
			(at 0 0 90)
			(layer "F.Fab")
			(effects
				(font
					(size 1.27 1.27)
				)
			)
		)
		(duplicate_pad_numbers_are_jumpers no)
		(pad "" thru_hole circle
			(at 2.29997 -5.649976 90)
			(size 2.8194 2.8194)
			(drill 2.4384)
			(layers "*.Cu" "*.Mask")
			(remove_unused_layers no)
			(clearance 0.127)
			(thermal_gap 0.127)
		)
		(pad "" thru_hole oval
			(at 2.29997 68.90004 90)
			(size 2.8194 1.5748)
			(drill oval 2.4384 1.1938)
			(layers "*.Cu" "*.Mask")
			(remove_unused_layers no)
			(clearance 0.127)
			(thermal_gap 0.127)
		)
		(pad "" thru_hole circle
			(at 2.29997 132.299964 90)
			(size 2.8194 2.8194)
			(drill 2.4384)
			(layers "*.Cu" "*.Mask")
			(remove_unused_layers no)
			(clearance 0.127)
			(thermal_gap 0.127)
		)
		(pad "1" smd rect
			(at 0 0 90)
			(size 1.8034 0.508)
			(layers "F.Cu" "F.Mask" "F.Paste")
			(net "P12V_NVDIMM_ABC")
		)
		(pad "2" smd rect
			(at 0 0.849884 90)
			(size 1.8034 0.508)
			(layers "F.Cu" "F.Mask" "F.Paste")
			(net "GND")
		)
		(pad "3" smd rect
			(at 0 1.700022 90)
			(size 1.8034 0.508)
			(layers "F.Cu" "F.Mask" "F.Paste")
			(net "M_B_DQ<5>")
		)
		(pad "4" smd rect
			(at 0 2.549906 90)
			(size 1.8034 0.508)
			(layers "F.Cu" "F.Mask" "F.Paste")
			(net "GND")
		)
		(pad "5" smd rect
			(at 0 3.400044 90)
			(size 1.8034 0.508)
			(layers "F.Cu" "F.Mask" "F.Paste")
			(net "M_B_DQ<1>")
		)
		(pad "6" smd rect
			(at 0 4.249928 90)
			(size 1.8034 0.508)
			(layers "F.Cu" "F.Mask" "F.Paste")
			(net "GND")
		)
		(pad "7" smd rect
			(at 0 5.100066 90)
			(size 1.8034 0.508)
			(layers "F.Cu" "F.Mask" "F.Paste")
			(net "M_B_DQS_DP<9>")
		)
		(pad "8" smd rect
			(at 0 5.94995 90)
			(size 1.8034 0.508)
			(layers "F.Cu" "F.Mask" "F.Paste")
			(net "M_B_DQS_DN<9>")
		)
		(pad "9" smd rect
			(at 0 6.800088 90)
			(size 1.8034 0.508)
			(layers "F.Cu" "F.Mask" "F.Paste")
			(net "GND")
		)
		(pad "10" smd rect
			(at 0 7.649972 90)
			(size 1.8034 0.508)
			(layers "F.Cu" "F.Mask" "F.Paste")
			(net "M_B_DQ<7>")
		)
		(pad "11" smd rect
			(at 0 8.50011 90)
			(size 1.8034 0.508)
			(layers "F.Cu" "F.Mask" "F.Paste")
			(net "GND")
		)
		(pad "12" smd rect
			(at 0 9.349994 90)
			(size 1.8034 0.508)
			(layers "F.Cu" "F.Mask" "F.Paste")
			(net "M_B_DQ<3>")
		)
		(pad "13" smd rect
			(at 0 10.199878 90)
			(size 1.8034 0.508)
			(layers "F.Cu" "F.Mask" "F.Paste")
			(net "GND")
		)
		(pad "14" smd rect
			(at 0 11.050016 90)
			(size 1.8034 0.508)
			(layers "F.Cu" "F.Mask" "F.Paste")
			(net "M_B_DQ<13>")
		)
		(pad "15" smd rect
			(at 0 11.8999 90)
			(size 1.8034 0.508)
			(layers "F.Cu" "F.Mask" "F.Paste")
			(net "GND")
		)
		(pad "16" smd rect
			(at 0 12.750038 90)
			(size 1.8034 0.508)
			(layers "F.Cu" "F.Mask" "F.Paste")
			(net "M_B_DQ<9>")
		)
		(pad "17" smd rect
			(at 0 13.599922 90)
			(size 1.8034 0.508)
			(layers "F.Cu" "F.Mask" "F.Paste")
			(net "GND")
		)
		(pad "18" smd rect
			(at 0 14.45006 90)
			(size 1.8034 0.508)
			(layers "F.Cu" "F.Mask" "F.Paste")
			(net "M_B_DQS_DP<10>")
		)
		(pad "19" smd rect
			(at 0 15.299944 90)
			(size 1.8034 0.508)
			(layers "F.Cu" "F.Mask" "F.Paste")
			(net "M_B_DQS_DN<10>")
		)
		(pad "20" smd rect
			(at 0 16.150082 90)
			(size 1.8034 0.508)
			(layers "F.Cu" "F.Mask" "F.Paste")
			(net "GND")
		)
		(pad "21" smd rect
			(at 0 16.999966 90)
			(size 1.8034 0.508)
			(layers "F.Cu" "F.Mask" "F.Paste")
			(net "M_B_DQ<15>")
		)
		(pad "22" smd rect
			(at 0 17.850104 90)
			(size 1.8034 0.508)
			(layers "F.Cu" "F.Mask" "F.Paste")
			(net "GND")
		)
		(pad "23" smd rect
			(at 0 18.699988 90)
			(size 1.8034 0.508)
			(layers "F.Cu" "F.Mask" "F.Paste")
			(net "M_B_DQ<11>")
		)
		(pad "24" smd rect
			(at 0 19.550126 90)
			(size 1.8034 0.508)
			(layers "F.Cu" "F.Mask" "F.Paste")
			(net "GND")
		)
		(pad "25" smd rect
			(at 0 20.40001 90)
			(size 1.8034 0.508)
			(layers "F.Cu" "F.Mask" "F.Paste")
			(net "M_B_DQ<21>")
		)
		(pad "26" smd rect
			(at 0 21.249894 90)
			(size 1.8034 0.508)
			(layers "F.Cu" "F.Mask" "F.Paste")
			(net "GND")
		)
		(pad "27" smd rect
			(at 0 22.100032 90)
			(size 1.8034 0.508)
			(layers "F.Cu" "F.Mask" "F.Paste")
			(net "M_B_DQ<17>")
		)
		(pad "28" smd rect
			(at 0 22.949916 90)
			(size 1.8034 0.508)
			(layers "F.Cu" "F.Mask" "F.Paste")
			(net "GND")
		)
		(pad "29" smd rect
			(at 0 23.800054 90)
			(size 1.8034 0.508)
			(layers "F.Cu" "F.Mask" "F.Paste")
			(net "M_B_DQS_DP<11>")
		)
		(pad "30" smd rect
			(at 0 24.649938 90)
			(size 1.8034 0.508)
			(layers "F.Cu" "F.Mask" "F.Paste")
			(net "M_B_DQS_DN<11>")
		)
		(pad "31" smd rect
			(at 0 25.500076 90)
			(size 1.8034 0.508)
			(layers "F.Cu" "F.Mask" "F.Paste")
			(net "GND")
		)
		(pad "32" smd rect
			(at 0 26.34996 90)
			(size 1.8034 0.508)
			(layers "F.Cu" "F.Mask" "F.Paste")
			(net "M_B_DQ<23>")
		)
		(pad "33" smd rect
			(at 0 27.200098 90)
			(size 1.8034 0.508)
			(layers "F.Cu" "F.Mask" "F.Paste")
			(net "GND")
		)
		(pad "34" smd rect
			(at 0 28.049982 90)
			(size 1.8034 0.508)
			(layers "F.Cu" "F.Mask" "F.Paste")
			(net "M_B_DQ<19>")
		)
		(pad "35" smd rect
			(at 0 28.90012 90)
			(size 1.8034 0.508)
			(layers "F.Cu" "F.Mask" "F.Paste")
			(net "GND")
		)
		(pad "36" smd rect
			(at 0 29.750004 90)
			(size 1.8034 0.508)
			(layers "F.Cu" "F.Mask" "F.Paste")
			(net "M_B_DQ<29>")
		)
		(pad "37" smd rect
			(at 0 30.599888 90)
			(size 1.8034 0.508)
			(layers "F.Cu" "F.Mask" "F.Paste")
			(net "GND")
		)
		(pad "38" smd rect
			(at 0 31.450026 90)
			(size 1.8034 0.508)
			(layers "F.Cu" "F.Mask" "F.Paste")
			(net "M_B_DQ<25>")
		)
		(pad "39" smd rect
			(at 0 32.29991 90)
			(size 1.8034 0.508)
			(layers "F.Cu" "F.Mask" "F.Paste")
			(net "GND")
		)
		(pad "40" smd rect
			(at 0 33.150048 90)
			(size 1.8034 0.508)
			(layers "F.Cu" "F.Mask" "F.Paste")
			(net "M_B_DQS_DP<12>")
		)
		(pad "41" smd rect
			(at 0 33.999932 90)
			(size 1.8034 0.508)
			(layers "F.Cu" "F.Mask" "F.Paste")
			(net "M_B_DQS_DN<12>")
		)
		(pad "42" smd rect
			(at 0 34.85007 90)
			(size 1.8034 0.508)
			(layers "F.Cu" "F.Mask" "F.Paste")
			(net "GND")
		)
		(pad "43" smd rect
			(at 0 35.699954 90)
			(size 1.8034 0.508)
			(layers "F.Cu" "F.Mask" "F.Paste")
			(net "M_B_DQ<31>")
		)
		(pad "44" smd rect
			(at 0 36.550092 90)
			(size 1.8034 0.508)
			(layers "F.Cu" "F.Mask" "F.Paste")
			(net "GND")
		)
		(pad "45" smd rect
			(at 0 37.399976 90)
			(size 1.8034 0.508)
			(layers "F.Cu" "F.Mask" "F.Paste")
			(net "M_B_DQ<27>")
		)
		(pad "46" smd rect
			(at 0 38.250114 90)
			(size 1.8034 0.508)
			(layers "F.Cu" "F.Mask" "F.Paste")
			(net "GND")
		)
		(pad "47" smd rect
			(at 0 39.099998 90)
			(size 1.8034 0.508)
			(layers "F.Cu" "F.Mask" "F.Paste")
			(net "M_B_ECC<5>")
		)
		(pad "48" smd rect
			(at 0 39.949882 90)
			(size 1.8034 0.508)
			(layers "F.Cu" "F.Mask" "F.Paste")
			(net "GND")
		)
	)
)
